# T6G (Grand Teton) — schematic netlist excerpt (pin names and nets, part order shuffled) for the footprints in the layout excerpt that follows; sources: Cadence DE-HDL packaged netlist, KiCad conversion of 04192023_DAF0TMB3IC0_F0TG_MB_C_brd_V02_OCP.brd

R8381  Q_RES  0 5% CHIP  pkg 0402LF  page 224 : A = SMB_SCM_2_R2_SCL ; B = PVDD11_S3_P1_PMSCL_R
PR46  Q_RES  1.5 1% EMPTY  pkg 0402LF  page 213 : A = SW_PVDDCR_CPU0_P1_SW5_RC ; B = GND

(kicad_pcb
	(version 20260206)
	(generator "pcbnew")
	(generator_version "10.0")
	(general
		(thickness 1.6)
		(legacy_teardrops no)
	)
	(paper "A4")
	(title_block
		(title "04192023_DAF0TMB3IC0_F0TG_MB_C_brd_V02_OCP.brd")
		(comment 1 "Grand Teton / footprints 1199-1200 of 8354")
	)
	(layers
		(0 "F.Cu" signal "TOP")
		(4 "In1.Cu" signal "GND")
		(6 "In2.Cu" signal "IN1")
		(8 "In3.Cu" signal "GND1")
		(10 "In4.Cu" signal "IN2")
		(12 "In5.Cu" signal "GND2")
		(14 "In6.Cu" signal "IN3")
		(16 "In7.Cu" signal "GND3")
		(18 "In8.Cu" signal "VCC")
		(20 "In9.Cu" signal "VCC1")
		(22 "In10.Cu" signal "GND4")
		(24 "In11.Cu" signal "IN4")
		(26 "In12.Cu" signal "GND5")
		(28 "In13.Cu" signal "IN5")
		(30 "In14.Cu" signal "GND6")
		(32 "In15.Cu" signal "IN6")
		(34 "In16.Cu" signal "GND7")
		(2 "B.Cu" signal "BOTTOM")
		(9 "F.Adhes" user "F.Adhesive")
		(11 "B.Adhes" user "B.Adhesive")
		(13 "F.Paste" user "Package Geometry/Pastemask Top")
		(15 "B.Paste" user "Package Geometry/Pastemask Bottom")
		(5 "F.SilkS" user "Ref Des/Silkscreen Top")
		(7 "B.SilkS" user "Ref Des/Silkscreen Bottom")
		(1 "F.Mask" user "Board Geometry/Soldermask Top")
		(3 "B.Mask" user "Board Geometry/Soldermask Bottom")
		(17 "Dwgs.User" user "User.Drawings")
		(19 "Cmts.User" user "User.Comments")
		(21 "Eco1.User" user "User.Eco1")
		(23 "Eco2.User" user "User.Eco2")
		(25 "Edge.Cuts" user "Board Geometry/Outline")
		(27 "Margin" user)
		(31 "F.CrtYd" user "Package Geometry/Place Bound Top")
		(29 "B.CrtYd" user "Package Geometry/Place Bound Bottom")
		(35 "F.Fab" user "Ref Des/Assembly Top")
		(33 "B.Fab" user "Ref Des/Assembly Bottom")
	)
	(footprint ""
		(layer "F.Cu")
		(at 160.06953 -352.668078 -90)
		(property "Reference" "R8381"
			(at 0 0 270)
			(layer "F.SilkS")
			(hide yes)
			(effects
				(font
					(size 1.27 1.27)
				)
			)
		)
		(property "Value" ""
			(at 0 0 270)
			(layer "F.Fab")
			(effects
				(font
					(size 1.27 1.27)
				)
			)
		)
		(duplicate_pad_numbers_are_jumpers no)
		(fp_line
			(start -0.7874 0.4064)
			(end -0.7874 -0.4064)
			(stroke
				(width 0.1524)
				(type default)
			)
			(layer "F.SilkS")
		)
		(fp_line
			(start 0.7874 0.4064)
			(end -0.7874 0.4064)
			(stroke
				(width 0.1524)
				(type default)
			)
			(layer "F.SilkS")
		)
		(fp_line
			(start -0.7874 -0.4064)
			(end 0.7874 -0.4064)
			(stroke
				(width 0.1524)
				(type default)
			)
			(layer "F.SilkS")
		)
		(fp_line
			(start 0.7874 -0.4064)
			(end 0.7874 0.4064)
			(stroke
				(width 0.1524)
				(type default)
			)
			(layer "F.SilkS")
		)
		(fp_line
			(start -0.67945 0.3048)
			(end -0.67945 -0.305054)
			(stroke
				(width 0.1)
				(type default)
			)
			(layer "F.Fab")
		)
		(fp_line
			(start -0.12065 0.3048)
			(end -0.67945 0.3048)
			(stroke
				(width 0.1)
				(type default)
			)
			(layer "F.Fab")
		)
		(fp_line
			(start 0.120396 0.3048)
			(end 0.120396 0.2794)
			(stroke
				(width 0.1)
				(type default)
			)
			(layer "F.Fab")
		)
		(fp_line
			(start 0.67945 0.3048)
			(end 0.120396 0.3048)
			(stroke
				(width 0.1)
				(type default)
			)
			(layer "F.Fab")
		)
		(fp_line
			(start -0.12065 0.2794)
			(end -0.12065 0.3048)
			(stroke
				(width 0.1)
				(type default)
			)
			(layer "F.Fab")
		)
		(fp_line
			(start 0.120396 0.2794)
			(end -0.12065 0.2794)
			(stroke
				(width 0.1)
				(type default)
			)
			(layer "F.Fab")
		)
		(fp_line
			(start -0.12065 -0.2794)
			(end 0.12065 -0.2794)
			(stroke
				(width 0.1)
				(type default)
			)
			(layer "F.Fab")
		)
		(fp_line
			(start 0.12065 -0.2794)
			(end 0.12065 -0.3048)
			(stroke
				(width 0.1)
				(type default)
			)
			(layer "F.Fab")
		)
		(fp_line
			(start 0.12065 -0.3048)
			(end 0.67945 -0.3048)
			(stroke
				(width 0.1)
				(type default)
			)
			(layer "F.Fab")
		)
		(fp_line
			(start 0.67945 -0.3048)
			(end 0.67945 0.3048)
			(stroke
				(width 0.1)
				(type default)
			)
			(layer "F.Fab")
		)
		(fp_line
			(start -0.67945 -0.305054)
			(end -0.12065 -0.305054)
			(stroke
				(width 0.1)
				(type default)
			)
			(layer "F.Fab")
		)
		(fp_line
			(start -0.12065 -0.305054)
			(end -0.12065 -0.2794)
			(stroke
				(width 0.1)
				(type default)
			)
			(layer "F.Fab")
		)
		(pad "1" smd circle
			(at -0.40005 0 270)
			(size 0 0)
			(layers "F.Cu" "F.Mask" "F.Paste")
			(net "SMB_SCM_2_R2_SCL")
		)
		(pad "2" smd circle
			(at 0.40005 0 270)
			(size 0 0)
			(layers "F.Cu" "F.Mask" "F.Paste")
			(net "PVDD11_S3_P1_PMSCL_R")
		)
	)
	(footprint ""
		(layer "F.Cu")
		(at 77.638148 -179.360068 -90)
		(property "Reference" "PR46"
			(at 0 0 270)
			(layer "F.SilkS")
			(hide yes)
			(effects
				(font
					(size 1.27 1.27)
				)
			)
		)
		(property "Value" ""
			(at 0 0 270)
			(layer "F.Fab")
			(effects
				(font
					(size 1.27 1.27)
				)
			)
		)
		(duplicate_pad_numbers_are_jumpers no)
		(fp_line
			(start -0.7874 0.4064)
			(end -0.7874 -0.4064)
			(stroke
				(width 0.1524)
				(type default)
			)
			(layer "F.SilkS")
		)
		(fp_line
			(start 0.7874 0.4064)
			(end -0.7874 0.4064)
			(stroke
				(width 0.1524)
				(type default)
			)
			(layer "F.SilkS")
		)
		(fp_line
			(start -0.7874 -0.4064)
			(end 0.7874 -0.4064)
			(stroke
				(width 0.1524)
				(type default)
			)
			(layer "F.SilkS")
		)
		(fp_line
			(start 0.7874 -0.4064)
			(end 0.7874 0.4064)
			(stroke
				(width 0.1524)
				(type default)
			)
			(layer "F.SilkS")
		)
		(fp_line
			(start -0.67945 0.3048)
			(end -0.67945 -0.305054)
			(stroke
				(width 0.1)
				(type default)
			)
			(layer "F.Fab")
		)
		(fp_line
			(start -0.12065 0.3048)
			(end -0.67945 0.3048)
			(stroke
				(width 0.1)
				(type default)
			)
			(layer "F.Fab")
		)
		(fp_line
			(start 0.120396 0.3048)
			(end 0.120396 0.2794)
			(stroke
				(width 0.1)
				(type default)
			)
			(layer "F.Fab")
		)
		(fp_line
			(start 0.67945 0.3048)
			(end 0.120396 0.3048)
			(stroke
				(width 0.1)
				(type default)
			)
			(layer "F.Fab")
		)
		(fp_line
			(start -0.12065 0.2794)
			(end -0.12065 0.3048)
			(stroke
				(width 0.1)
				(type default)
			)
			(layer "F.Fab")
		)
		(fp_line
			(start 0.120396 0.2794)
			(end -0.12065 0.2794)
			(stroke
				(width 0.1)
				(type default)
			)
			(layer "F.Fab")
		)
		(fp_line
			(start -0.12065 -0.2794)
			(end 0.12065 -0.2794)
			(stroke
				(width 0.1)
				(type default)
			)
			(layer "F.Fab")
		)
		(fp_line
			(start 0.12065 -0.2794)
			(end 0.12065 -0.3048)
			(stroke
				(width 0.1)
				(type default)
			)
			(layer "F.Fab")
		)
		(fp_line
			(start 0.12065 -0.3048)
			(end 0.67945 -0.3048)
			(stroke
				(width 0.1)
				(type default)
			)
			(layer "F.Fab")
		)
		(fp_line
			(start 0.67945 -0.3048)
			(end 0.67945 0.3048)
			(stroke
				(width 0.1)
				(type default)
			)
			(layer "F.Fab")
		)
		(fp_line
			(start -0.67945 -0.305054)
			(end -0.12065 -0.305054)
			(stroke
				(width 0.1)
				(type default)
			)
			(layer "F.Fab")
		)
		(fp_line
			(start -0.12065 -0.305054)
			(end -0.12065 -0.2794)
			(stroke
				(width 0.1)
				(type default)
			)
			(layer "F.Fab")
		)
		(pad "1" smd circle
			(at -0.40005 0 270)
			(size 0 0)
			(layers "F.Cu" "F.Mask" "F.Paste")
			(net "SW_PVDDCR_CPU0_P1_SW5_RC")
		)
		(pad "2" smd circle
			(at 0.40005 0 270)
			(size 0 0)
			(layers "F.Cu" "F.Mask" "F.Paste")
			(net "GND")
		)
	)
)
